# T6G (Grand Teton) — schematic netlist excerpt (pin names and nets, part order shuffled) for the footprints in the layout excerpt that follows; sources: Cadence DE-HDL packaged netlist, KiCad conversion of 04192023_DAF0TMB3IC0_F0TG_MB_C_brd_V02_OCP.brd

R607  Q_RES  0 5% CHIP  pkg 0402LF  page 77 : A = SPI_CPU0_LVC3_D3 ; B = SPI_CPU0_LVC3_SCM_D3
PC148  Q_CAP  0.1UF 25V 10% X7R  pkg 0402  page 205 : A = P12V_AUX ; B = GND

(kicad_pcb
	(version 20260206)
	(generator "pcbnew")
	(generator_version "10.0")
	(general
		(thickness 1.6)
		(legacy_teardrops no)
	)
	(paper "A4")
	(title_block
		(title "04192023_DAF0TMB3IC0_F0TG_MB_C_brd_V02_OCP.brd")
		(comment 1 "Grand Teton / footprints 4363-4364 of 8354")
	)
	(layers
		(0 "F.Cu" signal "TOP")
		(4 "In1.Cu" signal "GND")
		(6 "In2.Cu" signal "IN1")
		(8 "In3.Cu" signal "GND1")
		(10 "In4.Cu" signal "IN2")
		(12 "In5.Cu" signal "GND2")
		(14 "In6.Cu" signal "IN3")
		(16 "In7.Cu" signal "GND3")
		(18 "In8.Cu" signal "VCC")
		(20 "In9.Cu" signal "VCC1")
		(22 "In10.Cu" signal "GND4")
		(24 "In11.Cu" signal "IN4")
		(26 "In12.Cu" signal "GND5")
		(28 "In13.Cu" signal "IN5")
		(30 "In14.Cu" signal "GND6")
		(32 "In15.Cu" signal "IN6")
		(34 "In16.Cu" signal "GND7")
		(2 "B.Cu" signal "BOTTOM")
		(9 "F.Adhes" user "F.Adhesive")
		(11 "B.Adhes" user "B.Adhesive")
		(13 "F.Paste" user "Package Geometry/Pastemask Top")
		(15 "B.Paste" user "Package Geometry/Pastemask Bottom")
		(5 "F.SilkS" user "Ref Des/Silkscreen Top")
		(7 "B.SilkS" user "Ref Des/Silkscreen Bottom")
		(1 "F.Mask" user "Board Geometry/Soldermask Top")
		(3 "B.Mask" user "Board Geometry/Soldermask Bottom")
		(17 "Dwgs.User" user "User.Drawings")
		(19 "Cmts.User" user "User.Comments")
		(21 "Eco1.User" user "User.Eco1")
		(23 "Eco2.User" user "User.Eco2")
		(25 "Edge.Cuts" user "Board Geometry/Outline")
		(27 "Margin" user)
		(31 "F.CrtYd" user "Package Geometry/Place Bound Top")
		(29 "B.CrtYd" user "Package Geometry/Place Bound Bottom")
		(35 "F.Fab" user "Ref Des/Assembly Top")
		(33 "B.Fab" user "Ref Des/Assembly Bottom")
	)
	(footprint ""
		(layer "F.Cu")
		(at 257.501644 -138.448796 180)
		(property "Reference" "R607"
			(at 0 0 180)
			(layer "F.SilkS")
			(hide yes)
			(effects
				(font
					(size 1.27 1.27)
				)
			)
		)
		(property "Value" ""
			(at 0 0 180)
			(layer "F.Fab")
			(effects
				(font
					(size 1.27 1.27)
				)
			)
		)
		(duplicate_pad_numbers_are_jumpers no)
		(fp_line
			(start 0.7874 0.4064)
			(end -0.7874 0.4064)
			(stroke
				(width 0.1524)
				(type default)
			)
			(layer "F.SilkS")
		)
		(fp_line
			(start 0.7874 -0.4064)
			(end 0.7874 0.4064)
			(stroke
				(width 0.1524)
				(type default)
			)
			(layer "F.SilkS")
		)
		(fp_line
			(start -0.7874 0.4064)
			(end -0.7874 -0.4064)
			(stroke
				(width 0.1524)
				(type default)
			)
			(layer "F.SilkS")
		)
		(fp_line
			(start -0.7874 -0.4064)
			(end 0.7874 -0.4064)
			(stroke
				(width 0.1524)
				(type default)
			)
			(layer "F.SilkS")
		)
		(fp_line
			(start 0.67945 0.3048)
			(end 0.120396 0.3048)
			(stroke
				(width 0.1)
				(type default)
			)
			(layer "F.Fab")
		)
		(fp_line
			(start 0.67945 -0.3048)
			(end 0.67945 0.3048)
			(stroke
				(width 0.1)
				(type default)
			)
			(layer "F.Fab")
		)
		(fp_line
			(start 0.12065 -0.2794)
			(end 0.12065 -0.3048)
			(stroke
				(width 0.1)
				(type default)
			)
			(layer "F.Fab")
		)
		(fp_line
			(start 0.12065 -0.3048)
			(end 0.67945 -0.3048)
			(stroke
				(width 0.1)
				(type default)
			)
			(layer "F.Fab")
		)
		(fp_line
			(start 0.120396 0.3048)
			(end 0.120396 0.2794)
			(stroke
				(width 0.1)
				(type default)
			)
			(layer "F.Fab")
		)
		(fp_line
			(start 0.120396 0.2794)
			(end -0.12065 0.2794)
			(stroke
				(width 0.1)
				(type default)
			)
			(layer "F.Fab")
		)
		(fp_line
			(start -0.12065 0.3048)
			(end -0.67945 0.3048)
			(stroke
				(width 0.1)
				(type default)
			)
			(layer "F.Fab")
		)
		(fp_line
			(start -0.12065 0.2794)
			(end -0.12065 0.3048)
			(stroke
				(width 0.1)
				(type default)
			)
			(layer "F.Fab")
		)
		(fp_line
			(start -0.12065 -0.2794)
			(end 0.12065 -0.2794)
			(stroke
				(width 0.1)
				(type default)
			)
			(layer "F.Fab")
		)
		(fp_line
			(start -0.12065 -0.305054)
			(end -0.12065 -0.2794)
			(stroke
				(width 0.1)
				(type default)
			)
			(layer "F.Fab")
		)
		(fp_line
			(start -0.67945 0.3048)
			(end -0.67945 -0.305054)
			(stroke
				(width 0.1)
				(type default)
			)
			(layer "F.Fab")
		)
		(fp_line
			(start -0.67945 -0.305054)
			(end -0.12065 -0.305054)
			(stroke
				(width 0.1)
				(type default)
			)
			(layer "F.Fab")
		)
		(pad "1" smd circle
			(at -0.40005 0 180)
			(size 0 0)
			(layers "F.Cu" "F.Mask" "F.Paste")
			(net "SPI_CPU0_LVC3_D3")
		)
		(pad "2" smd circle
			(at 0.40005 0 180)
			(size 0 0)
			(layers "F.Cu" "F.Mask" "F.Paste")
			(net "SPI_CPU0_LVC3_SCM_D3")
		)
	)
	(footprint ""
		(layer "F.Cu")
		(at 291.816282 -364.891066)
		(property "Reference" "PC148"
			(at 0 0 0)
			(layer "F.SilkS")
			(hide yes)
			(effects
				(font
					(size 1.27 1.27)
				)
			)
		)
		(property "Value" ""
			(at 0 0 0)
			(layer "F.Fab")
			(effects
				(font
					(size 1.27 1.27)
				)
			)
		)
		(duplicate_pad_numbers_are_jumpers no)
		(fp_line
			(start -0.7874 -0.4064)
			(end 0.7874 -0.4064)
			(stroke
				(width 0.1524)
				(type default)
			)
			(layer "F.SilkS")
		)
		(fp_line
			(start -0.7874 0.4064)
			(end -0.7874 -0.4064)
			(stroke
				(width 0.1524)
				(type default)
			)
			(layer "F.SilkS")
		)
		(fp_line
			(start 0.7874 -0.4064)
			(end 0.7874 0.4064)
			(stroke
				(width 0.1524)
				(type default)
			)
			(layer "F.SilkS")
		)
		(fp_line
			(start 0.7874 0.4064)
			(end -0.7874 0.4064)
			(stroke
				(width 0.1524)
				(type default)
			)
			(layer "F.SilkS")
		)
		(fp_line
			(start -0.67945 -0.305054)
			(end -0.12065 -0.305054)
			(stroke
				(width 0.1)
				(type default)
			)
			(layer "F.Fab")
		)
		(fp_line
			(start -0.67945 0.3048)
			(end -0.67945 -0.305054)
			(stroke
				(width 0.1)
				(type default)
			)
			(layer "F.Fab")
		)
		(fp_line
			(start -0.12065 -0.305054)
			(end -0.12065 -0.2794)
			(stroke
				(width 0.1)
				(type default)
			)
			(layer "F.Fab")
		)
		(fp_line
			(start -0.12065 -0.2794)
			(end 0.12065 -0.2794)
			(stroke
				(width 0.1)
				(type default)
			)
			(layer "F.Fab")
		)
		(fp_line
			(start -0.12065 0.2794)
			(end -0.12065 0.3048)
			(stroke
				(width 0.1)
				(type default)
			)
			(layer "F.Fab")
		)
		(fp_line
			(start -0.12065 0.3048)
			(end -0.67945 0.3048)
			(stroke
				(width 0.1)
				(type default)
			)
			(layer "F.Fab")
		)
		(fp_line
			(start 0.120396 0.2794)
			(end -0.12065 0.2794)
			(stroke
				(width 0.1)
				(type default)
			)
			(layer "F.Fab")
		)
		(fp_line
			(start 0.120396 0.3048)
			(end 0.120396 0.2794)
			(stroke
				(width 0.1)
				(type default)
			)
			(layer "F.Fab")
		)
		(fp_line
			(start 0.12065 -0.3048)
			(end 0.67945 -0.3048)
			(stroke
				(width 0.1)
				(type default)
			)
			(layer "F.Fab")
		)
		(fp_line
			(start 0.12065 -0.2794)
			(end 0.12065 -0.3048)
			(stroke
				(width 0.1)
				(type default)
			)
			(layer "F.Fab")
		)
		(fp_line
			(start 0.67945 -0.3048)
			(end 0.67945 0.3048)
			(stroke
				(width 0.1)
				(type default)
			)
			(layer "F.Fab")
		)
		(fp_line
			(start 0.67945 0.3048)
			(end 0.120396 0.3048)
			(stroke
				(width 0.1)
				(type default)
			)
			(layer "F.Fab")
		)
		(pad "1" smd circle
			(at -0.40005 0)
			(size 0 0)
			(layers "F.Cu" "F.Mask" "F.Paste")
			(net "P12V_AUX")
		)
		(pad "2" smd circle
			(at 0.40005 0)
			(size 0 0)
			(layers "F.Cu" "F.Mask" "F.Paste")
			(net "GND")
		)
	)
)
